# BASEBOARD_FAB2 (Tioga Pass) — schematic netlist excerpt (pin names and nets, part order shuffled) for the footprints in the layout excerpt that follows; sources: Cadence DE-HDL packaged netlist, KiCad conversion of Wiwynn_Tioga_Pass_MB.brd

R8E32  RES  4.75K 1% CHIP  pkg 0402  page 157 : A = P3V3_STBY ; B = FP_NMI_BTN_OUT_R_N
C1R13  CAP  10UF 6.3V 20% X6S  pkg 0603  page 139 : A = P3V3_STBY ; B = GND
R1C1  RES  221 1.0% CHIP  pkg 0402  page 55 : A = SVID_ALERT1_CPU1_N ; B = SVID_ALERT1_CPU1_R_N

(kicad_pcb
	(version 20260206)
	(generator "pcbnew")
	(generator_version "10.0")
	(general
		(thickness 1.6)
		(legacy_teardrops no)
	)
	(paper "A4")
	(title_block
		(title "Wiwynn_Tioga_Pass_MB.brd")
		(comment 1 "Tioga Pass / footprints 3932-3934 of 4770")
	)
	(layers
		(0 "F.Cu" signal "TOP")
		(4 "In1.Cu" signal "L2GND")
		(6 "In2.Cu" signal "L3")
		(8 "In3.Cu" signal "L4GND")
		(10 "In4.Cu" signal "L5")
		(12 "In5.Cu" signal "L6GND")
		(14 "In6.Cu" signal "L7VCC")
		(16 "In7.Cu" signal "L8VCC")
		(18 "In8.Cu" signal "L9GND")
		(20 "In9.Cu" signal "L10")
		(22 "In10.Cu" signal "L11GND")
		(24 "In11.Cu" signal "L12")
		(26 "In12.Cu" signal "L13GND")
		(2 "B.Cu" signal "BOTTOM")
		(9 "F.Adhes" user "F.Adhesive")
		(11 "B.Adhes" user "B.Adhesive")
		(13 "F.Paste" user "Package Geometry/Pastemask Top")
		(15 "B.Paste" user "Package Geometry/Pastemask Bottom")
		(5 "F.SilkS" user "Ref Des/Silkscreen Top")
		(7 "B.SilkS" user "Ref Des/Silkscreen Bottom")
		(1 "F.Mask" user "Board Geometry/Soldermask Top")
		(3 "B.Mask" user "Board Geometry/Soldermask Bottom")
		(17 "Dwgs.User" user "User.Drawings")
		(19 "Cmts.User" user "User.Comments")
		(21 "Eco1.User" user "User.Eco1")
		(23 "Eco2.User" user "User.Eco2")
		(25 "Edge.Cuts" user "Board Geometry/Outline")
		(27 "Margin" user)
		(31 "F.CrtYd" user "Package Geometry/Place Bound Top")
		(29 "B.CrtYd" user "Package Geometry/Place Bound Bottom")
		(35 "F.Fab" user "Ref Des/Assembly Top")
		(33 "B.Fab" user "Ref Des/Assembly Bottom")
	)
	(footprint ""
		(layer "B.Cu")
		(at 485.267 -48.5775)
		(property "Reference" "C1R13"
			(at 0 0 0)
			(layer "B.SilkS")
			(hide yes)
			(effects
				(font
					(size 1.27 1.27)
				)
				(justify mirror)
			)
		)
		(property "Value" ""
			(at 0 0 0)
			(layer "B.Fab")
			(effects
				(font
					(size 1.27 1.27)
				)
				(justify mirror)
			)
		)
		(duplicate_pad_numbers_are_jumpers no)
		(fp_poly
			(pts
				(xy 0.4953 -0.2032) (xy -0.4953 -0.2032) (xy -0.4953 1.6002) (xy 0.4953 1.6002)
			)
			(stroke
				(width 0)
				(type default)
			)
			(fill no)
			(layer "B.CrtYd")
		)
		(fp_line
			(start -0.4953 -0.2032)
			(end -0.4953 1.6002)
			(stroke
				(width 0.1)
				(type default)
			)
			(layer "B.Fab")
		)
		(fp_line
			(start -0.4953 1.6002)
			(end 0.4953 1.6002)
			(stroke
				(width 0.1)
				(type default)
			)
			(layer "B.Fab")
		)
		(fp_line
			(start 0.4953 -0.2032)
			(end -0.4953 -0.2032)
			(stroke
				(width 0.1)
				(type default)
			)
			(layer "B.Fab")
		)
		(fp_line
			(start 0.4953 1.6002)
			(end 0.4953 -0.2032)
			(stroke
				(width 0.1)
				(type default)
			)
			(layer "B.Fab")
		)
		(pad "1" smd rect
			(at 0 0 180)
			(size 0.762 0.889)
			(layers "B.Cu" "B.Mask" "B.Paste")
			(net "P3V3_STBY")
		)
		(pad "2" smd rect
			(at 0 1.397 180)
			(size 0.762 0.889)
			(layers "B.Cu" "B.Mask" "B.Paste")
			(net "GND")
		)
		(zone
			(layer "B.Cu")
			(hatch none 0.5)
			(connect_pads
				(clearance 0)
			)
			(min_thickness 0.25)
			(keepout
				(tracks not_allowed)
				(vias allowed)
				(pads allowed)
				(copperpour not_allowed)
				(footprints allowed)
			)
			(placement
				(enabled no)
				(sheetname "")
			)
			(fill
				(thermal_gap 0.5)
				(thermal_bridge_width 0.5)
				(island_removal_mode 0)
			)
			(polygon
				(pts
					(xy 485.648 -48.133) (xy 484.886 -48.133) (xy 484.886 -47.625) (xy 485.648 -47.625)
				)
			)
		)
	)
	(footprint ""
		(layer "B.Cu")
		(at 411.2895 -11.000994 90)
		(property "Reference" "R8E32"
			(at 0 0 90)
			(layer "B.SilkS")
			(hide yes)
			(effects
				(font
					(size 1.27 1.27)
				)
				(justify mirror)
			)
		)
		(property "Value" ""
			(at 0 0 90)
			(layer "B.Fab")
			(effects
				(font
					(size 1.27 1.27)
				)
				(justify mirror)
			)
		)
		(duplicate_pad_numbers_are_jumpers no)
		(fp_poly
			(pts
				(xy 0.2794 -0.1016) (xy -0.2794 -0.1016) (xy -0.2794 0.9906) (xy 0.2794 0.9906)
			)
			(stroke
				(width 0)
				(type default)
			)
			(fill no)
			(layer "B.CrtYd")
		)
		(fp_line
			(start 0.2794 -0.1016)
			(end 0.2794 0.9906)
			(stroke
				(width 0.1)
				(type default)
			)
			(layer "B.Fab")
		)
		(fp_line
			(start -0.2794 -0.1016)
			(end 0.2794 -0.1016)
			(stroke
				(width 0.1)
				(type default)
			)
			(layer "B.Fab")
		)
		(fp_line
			(start 0.2794 0.9906)
			(end -0.2794 0.9906)
			(stroke
				(width 0.1)
				(type default)
			)
			(layer "B.Fab")
		)
		(fp_line
			(start -0.2794 0.9906)
			(end -0.2794 -0.1016)
			(stroke
				(width 0.1)
				(type default)
			)
			(layer "B.Fab")
		)
		(pad "1" smd rect
			(at 0 0 270)
			(size 0.508 0.508)
			(layers "B.Cu" "B.Mask" "B.Paste")
			(net "P3V3_STBY")
		)
		(pad "2" smd rect
			(at 0 0.889 270)
			(size 0.508 0.508)
			(layers "B.Cu" "B.Mask" "B.Paste")
			(net "FP_NMI_BTN_OUT_R_N")
		)
		(zone
			(layer "B.Cu")
			(hatch none 0.5)
			(connect_pads
				(clearance 0)
			)
			(min_thickness 0.25)
			(keepout
				(tracks allowed)
				(vias not_allowed)
				(pads allowed)
				(copperpour not_allowed)
				(footprints allowed)
			)
			(placement
				(enabled no)
				(sheetname "")
			)
			(fill
				(thermal_gap 0.5)
				(thermal_bridge_width 0.5)
				(island_removal_mode 0)
			)
			(polygon
				(pts
					(xy 411.5435 -11.254994) (xy 411.5435 -10.746994) (xy 411.9245 -10.746994) (xy 411.9245 -11.254994)
				)
			)
		)
		(zone
			(layer "B.Cu")
			(hatch none 0.5)
			(connect_pads
				(clearance 0)
			)
			(min_thickness 0.25)
			(keepout
				(tracks not_allowed)
				(vias allowed)
				(pads allowed)
				(copperpour not_allowed)
				(footprints allowed)
			)
			(placement
				(enabled no)
				(sheetname "")
			)
			(fill
				(thermal_gap 0.5)
				(thermal_bridge_width 0.5)
				(island_removal_mode 0)
			)
			(polygon
				(pts
					(xy 411.9245 -11.254994) (xy 411.9245 -10.746994) (xy 411.5435 -10.746994) (xy 411.5435 -11.254994)
				)
			)
		)
	)
	(footprint ""
		(layer "B.Cu")
		(at 39.329614 -107.807506 -90)
		(property "Reference" "R1C1"
			(at 0 0 90)
			(layer "B.SilkS")
			(hide yes)
			(effects
				(font
					(size 1.27 1.27)
				)
				(justify mirror)
			)
		)
		(property "Value" ""
			(at 0 0 90)
			(layer "B.Fab")
			(effects
				(font
					(size 1.27 1.27)
				)
				(justify mirror)
			)
		)
		(duplicate_pad_numbers_are_jumpers no)
		(fp_poly
			(pts
				(xy 0.2794 -0.1016) (xy -0.2794 -0.1016) (xy -0.2794 0.9906) (xy 0.2794 0.9906)
			)
			(stroke
				(width 0)
				(type default)
			)
			(fill no)
			(layer "B.CrtYd")
		)
		(fp_line
			(start -0.2794 0.9906)
			(end -0.2794 -0.1016)
			(stroke
				(width 0.1)
				(type default)
			)
			(layer "B.Fab")
		)
		(fp_line
			(start 0.2794 0.9906)
			(end -0.2794 0.9906)
			(stroke
				(width 0.1)
				(type default)
			)
			(layer "B.Fab")
		)
		(fp_line
			(start -0.2794 -0.1016)
			(end 0.2794 -0.1016)
			(stroke
				(width 0.1)
				(type default)
			)
			(layer "B.Fab")
		)
		(fp_line
			(start 0.2794 -0.1016)
			(end 0.2794 0.9906)
			(stroke
				(width 0.1)
				(type default)
			)
			(layer "B.Fab")
		)
		(pad "1" smd rect
			(at 0 0 90)
			(size 0.508 0.508)
			(layers "B.Cu" "B.Mask" "B.Paste")
			(net "SVID_ALERT1_CPU1_N")
		)
		(pad "2" smd rect
			(at 0 0.889 90)
			(size 0.508 0.508)
			(layers "B.Cu" "B.Mask" "B.Paste")
			(net "SVID_ALERT1_CPU1_R_N")
		)
		(zone
			(layer "B.Cu")
			(hatch none 0.5)
			(connect_pads
				(clearance 0)
			)
			(min_thickness 0.25)
			(keepout
				(tracks not_allowed)
				(vias allowed)
				(pads allowed)
				(copperpour not_allowed)
				(footprints allowed)
			)
			(placement
				(enabled no)
				(sheetname "")
			)
			(fill
				(thermal_gap 0.5)
				(thermal_bridge_width 0.5)
				(island_removal_mode 0)
			)
			(polygon
				(pts
					(xy 38.694614 -107.553506) (xy 38.694614 -108.061506) (xy 39.075614 -108.061506) (xy 39.075614 -107.553506)
				)
			)
		)
		(zone
			(layer "B.Cu")
			(hatch none 0.5)
			(connect_pads
				(clearance 0)
			)
			(min_thickness 0.25)
			(keepout
				(tracks allowed)
				(vias not_allowed)
				(pads allowed)
				(copperpour not_allowed)
				(footprints allowed)
			)
			(placement
				(enabled no)
				(sheetname "")
			)
			(fill
				(thermal_gap 0.5)
				(thermal_bridge_width 0.5)
				(island_removal_mode 0)
			)
			(polygon
				(pts
					(xy 39.075614 -107.553506) (xy 39.075614 -108.061506) (xy 38.694614 -108.061506) (xy 38.694614 -107.553506)
				)
			)
		)
	)
)
